(kicad_pcb
	(version 20260206)
	(generator "pcbnew")
	(generator_version "10.0")
	(general
		(thickness 1.6)
		(legacy_teardrops no)
	)
	(paper "A4")
	(title_block
		(title "01162023_DA0F0TEBIF0_F0T_Expander_BD_F_brd_V02_OCP.brd")
		(comment 1 "Grand Teton / footprints 5638-5643 of 9728")
	)
	(layers
		(0 "F.Cu" signal "TOP")
		(4 "In1.Cu" signal "GND")
		(6 "In2.Cu" signal "VCC")
		(8 "In3.Cu" signal "VCC1")
		(10 "In4.Cu" signal "GND1")
		(12 "In5.Cu" signal "IN1")
		(14 "In6.Cu" signal "GND2")
		(16 "In7.Cu" signal "IN2")
		(18 "In8.Cu" signal "GND3")
		(20 "In9.Cu" signal "IN3")
		(22 "In10.Cu" signal "GND4")
		(24 "In11.Cu" signal "IN4")
		(26 "In12.Cu" signal "GND5")
		(28 "In13.Cu" signal "IN5")
		(30 "In14.Cu" signal "GND6")
		(32 "In15.Cu" signal "IN6")
		(34 "In16.Cu" signal "GND7")
		(2 "B.Cu" signal "BOTTOM")
		(9 "F.Adhes" user "F.Adhesive")
		(11 "B.Adhes" user "B.Adhesive")
		(13 "F.Paste" user "Package Geometry/Pastemask Top")
		(15 "B.Paste" user "Package Geometry/Pastemask Bottom")
		(5 "F.SilkS" user "Ref Des/Silkscreen Top")
		(7 "B.SilkS" user "Ref Des/Silkscreen Bottom")
		(1 "F.Mask" user "Board Geometry/Soldermask Top")
		(3 "B.Mask" user "Board Geometry/Soldermask Bottom")
		(17 "Dwgs.User" user "User.Drawings")
		(19 "Cmts.User" user "User.Comments")
		(21 "Eco1.User" user "User.Eco1")
		(23 "Eco2.User" user "User.Eco2")
		(25 "Edge.Cuts" user "Board Geometry/Outline")
		(27 "Margin" user)
		(31 "F.CrtYd" user "Package Geometry/Place Bound Top")
		(29 "B.CrtYd" user "Package Geometry/Place Bound Bottom")
		(35 "F.Fab" user "Ref Des/Assembly Top")
		(33 "B.Fab" user "Ref Des/Assembly Bottom")
	)
	(footprint ""
		(layer "F.Cu")
		(at 199.756268 -61.487812 180)
		(property "Reference" "R5983"
			(at 0 0 180)
			(layer "F.SilkS")
			(hide yes)
			(effects
				(font
					(size 1.27 1.27)
				)
			)
		)
		(property "Value" ""
			(at 0 0 180)
			(layer "F.Fab")
			(effects
				(font
					(size 1.27 1.27)
				)
			)
		)
		(duplicate_pad_numbers_are_jumpers no)
		(fp_line
			(start 0.7874 0.4064)
			(end -0.7874 0.4064)
			(stroke
				(width 0.1524)
				(type default)
			)
			(layer "F.SilkS")
		)
		(fp_line
			(start 0.7874 -0.4064)
			(end 0.7874 0.4064)
			(stroke
				(width 0.1524)
				(type default)
			)
			(layer "F.SilkS")
		)
		(fp_line
			(start -0.7874 0.4064)
			(end -0.7874 -0.4064)
			(stroke
				(width 0.1524)
				(type default)
			)
			(layer "F.SilkS")
		)
		(fp_line
			(start -0.7874 -0.4064)
			(end 0.7874 -0.4064)
			(stroke
				(width 0.1524)
				(type default)
			)
			(layer "F.SilkS")
		)
		(fp_line
			(start 0.67945 0.3048)
			(end 0.120396 0.3048)
			(stroke
				(width 0.1)
				(type default)
			)
			(layer "F.Fab")
		)
		(fp_line
			(start 0.67945 -0.3048)
			(end 0.67945 0.3048)
			(stroke
				(width 0.1)
				(type default)
			)
			(layer "F.Fab")
		)
		(fp_line
			(start 0.12065 -0.2794)
			(end 0.12065 -0.3048)
			(stroke
				(width 0.1)
				(type default)
			)
			(layer "F.Fab")
		)
		(fp_line
			(start 0.12065 -0.3048)
			(end 0.67945 -0.3048)
			(stroke
				(width 0.1)
				(type default)
			)
			(layer "F.Fab")
		)
		(fp_line
			(start 0.120396 0.3048)
			(end 0.120396 0.2794)
			(stroke
				(width 0.1)
				(type default)
			)
			(layer "F.Fab")
		)
		(fp_line
			(start 0.120396 0.2794)
			(end -0.12065 0.2794)
			(stroke
				(width 0.1)
				(type default)
			)
			(layer "F.Fab")
		)
		(fp_line
			(start -0.12065 0.3048)
			(end -0.67945 0.3048)
			(stroke
				(width 0.1)
				(type default)
			)
			(layer "F.Fab")
		)
		(fp_line
			(start -0.12065 0.2794)
			(end -0.12065 0.3048)
			(stroke
				(width 0.1)
				(type default)
			)
			(layer "F.Fab")
		)
		(fp_line
			(start -0.12065 -0.2794)
			(end 0.12065 -0.2794)
			(stroke
				(width 0.1)
				(type default)
			)
			(layer "F.Fab")
		)
		(fp_line
			(start -0.12065 -0.305054)
			(end -0.12065 -0.2794)
			(stroke
				(width 0.1)
				(type default)
			)
			(layer "F.Fab")
		)
		(fp_line
			(start -0.67945 0.3048)
			(end -0.67945 -0.305054)
			(stroke
				(width 0.1)
				(type default)
			)
			(layer "F.Fab")
		)
		(fp_line
			(start -0.67945 -0.305054)
			(end -0.12065 -0.305054)
			(stroke
				(width 0.1)
				(type default)
			)
			(layer "F.Fab")
		)
		(pad "1" smd circle
			(at -0.40005 0 180)
			(size 0 0)
			(layers "F.Cu" "F.Mask" "F.Paste")
			(net "P3V3_AUX")
		)
		(pad "2" smd circle
			(at 0.40005 0 180)
			(size 0 0)
			(layers "F.Cu" "F.Mask" "F.Paste")
			(net "PWRGD_P12V_SSD7_D")
		)
	)
	(footprint ""
		(layer "F.Cu")
		(at 214.75954 -61.612526)
		(property "Reference" "PD20"
			(at -3.7084 -2.733548 0)
			(unlocked yes)
			(layer "F.SilkS")
			(effects
				(font
					(size 0.7874 0.5842)
					(thickness 0.1524)
				)
				(justify left)
			)
		)
		(property "Value" ""
			(at 0 0 0)
			(layer "F.Fab")
			(effects
				(font
					(size 1.27 1.27)
				)
			)
		)
		(duplicate_pad_numbers_are_jumpers no)
		(fp_line
			(start -3.656584 -1.970024)
			(end -3.656584 1.970024)
			(stroke
				(width 0.1524)
				(type default)
			)
			(layer "F.SilkS")
		)
		(fp_line
			(start -3.656584 1.970024)
			(end 4.240784 1.970024)
			(stroke
				(width 0.1524)
				(type default)
			)
			(layer "F.SilkS")
		)
		(fp_line
			(start 4.240784 -1.970024)
			(end -3.656584 -1.970024)
			(stroke
				(width 0.1524)
				(type default)
			)
			(layer "F.SilkS")
		)
		(fp_line
			(start 4.240784 1.970024)
			(end 4.240784 -1.970024)
			(stroke
				(width 0.1524)
				(type default)
			)
			(layer "F.SilkS")
		)
		(fp_poly
			(pts
				(xy 3.580384 1.970024) (xy 3.580384 -1.970024) (xy 4.240784 -1.970024) (xy 4.240784 1.970024)
			)
			(stroke
				(width 0)
				(type default)
			)
			(fill yes)
			(layer "F.SilkS")
		)
		(fp_line
			(start -2.3749 -1.970024)
			(end -2.3749 1.970024)
			(stroke
				(width 0.1)
				(type default)
			)
			(layer "F.Fab")
		)
		(fp_line
			(start -2.3749 1.970024)
			(end 2.3749 1.970024)
			(stroke
				(width 0.1)
				(type default)
			)
			(layer "F.Fab")
		)
		(fp_line
			(start 2.3749 -1.970024)
			(end -2.3749 -1.970024)
			(stroke
				(width 0.1)
				(type default)
			)
			(layer "F.Fab")
		)
		(fp_line
			(start 2.3749 1.970024)
			(end 2.3749 -1.970024)
			(stroke
				(width 0.1)
				(type default)
			)
			(layer "F.Fab")
		)
		(fp_text user "+"
			(at -4.9784 -0.23495 0)
			(unlocked yes)
			(layer "F.Fab")
			(effects
				(font
					(size 1.905 1.4224)
					(thickness 0.1524)
				)
				(justify left)
			)
		)
		(fp_text user "-"
			(at 4.1656 -0.23495 0)
			(unlocked yes)
			(layer "F.Fab")
			(effects
				(font
					(size 1.905 1.4224)
					(thickness 0.1524)
				)
				(justify left)
			)
		)
		(pad "A" smd rect
			(at -2.450084 0)
			(size 2.159 2.2606)
			(layers "F.Cu" "F.Mask" "F.Paste")
			(net "GND")
		)
		(pad "C" smd rect
			(at 2.450084 0)
			(size 2.159 2.2606)
			(layers "F.Cu" "F.Mask" "F.Paste")
			(net "P12V_AUX")
		)
	)
	(footprint ""
		(layer "F.Cu")
		(at 98.947224 -21.37156)
		(property "Reference" "C3896"
			(at 0 0 0)
			(layer "F.SilkS")
			(hide yes)
			(effects
				(font
					(size 1.27 1.27)
				)
			)
		)
		(property "Value" ""
			(at 0 0 0)
			(layer "F.Fab")
			(effects
				(font
					(size 1.27 1.27)
				)
			)
		)
		(duplicate_pad_numbers_are_jumpers no)
		(fp_line
			(start -0.7874 -0.4064)
			(end 0.7874 -0.4064)
			(stroke
				(width 0.1524)
				(type default)
			)
			(layer "F.SilkS")
		)
		(fp_line
			(start -0.7874 0.4064)
			(end -0.7874 -0.4064)
			(stroke
				(width 0.1524)
				(type default)
			)
			(layer "F.SilkS")
		)
		(fp_line
			(start 0.7874 -0.4064)
			(end 0.7874 0.4064)
			(stroke
				(width 0.1524)
				(type default)
			)
			(layer "F.SilkS")
		)
		(fp_line
			(start 0.7874 0.4064)
			(end -0.7874 0.4064)
			(stroke
				(width 0.1524)
				(type default)
			)
			(layer "F.SilkS")
		)
		(fp_line
			(start -0.67945 -0.305054)
			(end -0.12065 -0.305054)
			(stroke
				(width 0.1)
				(type default)
			)
			(layer "F.Fab")
		)
		(fp_line
			(start -0.67945 0.3048)
			(end -0.67945 -0.305054)
			(stroke
				(width 0.1)
				(type default)
			)
			(layer "F.Fab")
		)
		(fp_line
			(start -0.12065 -0.305054)
			(end -0.12065 -0.2794)
			(stroke
				(width 0.1)
				(type default)
			)
			(layer "F.Fab")
		)
		(fp_line
			(start -0.12065 -0.2794)
			(end 0.12065 -0.2794)
			(stroke
				(width 0.1)
				(type default)
			)
			(layer "F.Fab")
		)
		(fp_line
			(start -0.12065 0.2794)
			(end -0.12065 0.3048)
			(stroke
				(width 0.1)
				(type default)
			)
			(layer "F.Fab")
		)
		(fp_line
			(start -0.12065 0.3048)
			(end -0.67945 0.3048)
			(stroke
				(width 0.1)
				(type default)
			)
			(layer "F.Fab")
		)
		(fp_line
			(start 0.120396 0.2794)
			(end -0.12065 0.2794)
			(stroke
				(width 0.1)
				(type default)
			)
			(layer "F.Fab")
		)
		(fp_line
			(start 0.120396 0.3048)
			(end 0.120396 0.2794)
			(stroke
				(width 0.1)
				(type default)
			)
			(layer "F.Fab")
		)
		(fp_line
			(start 0.12065 -0.3048)
			(end 0.67945 -0.3048)
			(stroke
				(width 0.1)
				(type default)
			)
			(layer "F.Fab")
		)
		(fp_line
			(start 0.12065 -0.2794)
			(end 0.12065 -0.3048)
			(stroke
				(width 0.1)
				(type default)
			)
			(layer "F.Fab")
		)
		(fp_line
			(start 0.67945 -0.3048)
			(end 0.67945 0.3048)
			(stroke
				(width 0.1)
				(type default)
			)
			(layer "F.Fab")
		)
		(fp_line
			(start 0.67945 0.3048)
			(end 0.120396 0.3048)
			(stroke
				(width 0.1)
				(type default)
			)
			(layer "F.Fab")
		)
		(pad "1" smd circle
			(at -0.40005 0)
			(size 0 0)
			(layers "F.Cu" "F.Mask" "F.Paste")
			(net "P12V_SSD3")
		)
		(pad "2" smd circle
			(at 0.40005 0)
			(size 0 0)
			(layers "F.Cu" "F.Mask" "F.Paste")
			(net "GND")
		)
	)
	(footprint ""
		(layer "F.Cu")
		(at 235.623608 -141.640814)
		(property "Reference" "R4195"
			(at 0 0 0)
			(layer "F.SilkS")
			(hide yes)
			(effects
				(font
					(size 1.27 1.27)
				)
			)
		)
		(property "Value" ""
			(at 0 0 0)
			(layer "F.Fab")
			(effects
				(font
					(size 1.27 1.27)
				)
			)
		)
		(duplicate_pad_numbers_are_jumpers no)
		(fp_line
			(start -0.7874 -0.4064)
			(end 0.7874 -0.4064)
			(stroke
				(width 0.1524)
				(type default)
			)
			(layer "F.SilkS")
		)
		(fp_line
			(start -0.7874 0.4064)
			(end -0.7874 -0.4064)
			(stroke
				(width 0.1524)
				(type default)
			)
			(layer "F.SilkS")
		)
		(fp_line
			(start 0.7874 -0.4064)
			(end 0.7874 0.4064)
			(stroke
				(width 0.1524)
				(type default)
			)
			(layer "F.SilkS")
		)
		(fp_line
			(start 0.7874 0.4064)
			(end -0.7874 0.4064)
			(stroke
				(width 0.1524)
				(type default)
			)
			(layer "F.SilkS")
		)
		(fp_line
			(start -0.67945 -0.305054)
			(end -0.12065 -0.305054)
			(stroke
				(width 0.1)
				(type default)
			)
			(layer "F.Fab")
		)
		(fp_line
			(start -0.67945 0.3048)
			(end -0.67945 -0.305054)
			(stroke
				(width 0.1)
				(type default)
			)
			(layer "F.Fab")
		)
		(fp_line
			(start -0.12065 -0.305054)
			(end -0.12065 -0.2794)
			(stroke
				(width 0.1)
				(type default)
			)
			(layer "F.Fab")
		)
		(fp_line
			(start -0.12065 -0.2794)
			(end 0.12065 -0.2794)
			(stroke
				(width 0.1)
				(type default)
			)
			(layer "F.Fab")
		)
		(fp_line
			(start -0.12065 0.2794)
			(end -0.12065 0.3048)
			(stroke
				(width 0.1)
				(type default)
			)
			(layer "F.Fab")
		)
		(fp_line
			(start -0.12065 0.3048)
			(end -0.67945 0.3048)
			(stroke
				(width 0.1)
				(type default)
			)
			(layer "F.Fab")
		)
		(fp_line
			(start 0.120396 0.2794)
			(end -0.12065 0.2794)
			(stroke
				(width 0.1)
				(type default)
			)
			(layer "F.Fab")
		)
		(fp_line
			(start 0.120396 0.3048)
			(end 0.120396 0.2794)
			(stroke
				(width 0.1)
				(type default)
			)
			(layer "F.Fab")
		)
		(fp_line
			(start 0.12065 -0.3048)
			(end 0.67945 -0.3048)
			(stroke
				(width 0.1)
				(type default)
			)
			(layer "F.Fab")
		)
		(fp_line
			(start 0.12065 -0.2794)
			(end 0.12065 -0.3048)
			(stroke
				(width 0.1)
				(type default)
			)
			(layer "F.Fab")
		)
		(fp_line
			(start 0.67945 -0.3048)
			(end 0.67945 0.3048)
			(stroke
				(width 0.1)
				(type default)
			)
			(layer "F.Fab")
		)
		(fp_line
			(start 0.67945 0.3048)
			(end 0.120396 0.3048)
			(stroke
				(width 0.1)
				(type default)
			)
			(layer "F.Fab")
		)
		(pad "1" smd circle
			(at -0.40005 0)
			(size 0 0)
			(layers "F.Cu" "F.Mask" "F.Paste")
			(net "CK440_PEX_SS_EN")
		)
		(pad "2" smd circle
			(at 0.40005 0)
			(size 0 0)
			(layers "F.Cu" "F.Mask" "F.Paste")
			(net "P3V3")
		)
	)
	(footprint ""
		(layer "F.Cu")
		(at 263.147302 -36.686998 90)
		(property "Reference" "C3669"
			(at 0 0 90)
			(layer "F.SilkS")
			(hide yes)
			(effects
				(font
					(size 1.27 1.27)
				)
			)
		)
		(property "Value" ""
			(at 0 0 90)
			(layer "F.Fab")
			(effects
				(font
					(size 1.27 1.27)
				)
			)
		)
		(duplicate_pad_numbers_are_jumpers no)
		(fp_line
			(start 0.7874 -0.4064)
			(end 0.7874 0.4064)
			(stroke
				(width 0.1524)
				(type default)
			)
			(layer "F.SilkS")
		)
		(fp_line
			(start -0.7874 -0.4064)
			(end 0.7874 -0.4064)
			(stroke
				(width 0.1524)
				(type default)
			)
			(layer "F.SilkS")
		)
		(fp_line
			(start 0.7874 0.4064)
			(end -0.7874 0.4064)
			(stroke
				(width 0.1524)
				(type default)
			)
			(layer "F.SilkS")
		)
		(fp_line
			(start -0.7874 0.4064)
			(end -0.7874 -0.4064)
			(stroke
				(width 0.1524)
				(type default)
			)
			(layer "F.SilkS")
		)
		(fp_line
			(start -0.12065 -0.305054)
			(end -0.12065 -0.2794)
			(stroke
				(width 0.1)
				(type default)
			)
			(layer "F.Fab")
		)
		(fp_line
			(start -0.67945 -0.305054)
			(end -0.12065 -0.305054)
			(stroke
				(width 0.1)
				(type default)
			)
			(layer "F.Fab")
		)
		(fp_line
			(start 0.67945 -0.3048)
			(end 0.67945 0.3048)
			(stroke
				(width 0.1)
				(type default)
			)
			(layer "F.Fab")
		)
		(fp_line
			(start 0.12065 -0.3048)
			(end 0.67945 -0.3048)
			(stroke
				(width 0.1)
				(type default)
			)
			(layer "F.Fab")
		)
		(fp_line
			(start 0.12065 -0.2794)
			(end 0.12065 -0.3048)
			(stroke
				(width 0.1)
				(type default)
			)
			(layer "F.Fab")
		)
		(fp_line
			(start -0.12065 -0.2794)
			(end 0.12065 -0.2794)
			(stroke
				(width 0.1)
				(type default)
			)
			(layer "F.Fab")
		)
		(fp_line
			(start 0.120396 0.2794)
			(end -0.12065 0.2794)
			(stroke
				(width 0.1)
				(type default)
			)
			(layer "F.Fab")
		)
		(fp_line
			(start -0.12065 0.2794)
			(end -0.12065 0.3048)
			(stroke
				(width 0.1)
				(type default)
			)
			(layer "F.Fab")
		)
		(fp_line
			(start 0.67945 0.3048)
			(end 0.120396 0.3048)
			(stroke
				(width 0.1)
				(type default)
			)
			(layer "F.Fab")
		)
		(fp_line
			(start 0.120396 0.3048)
			(end 0.120396 0.2794)
			(stroke
				(width 0.1)
				(type default)
			)
			(layer "F.Fab")
		)
		(fp_line
			(start -0.12065 0.3048)
			(end -0.67945 0.3048)
			(stroke
				(width 0.1)
				(type default)
			)
			(layer "F.Fab")
		)
		(fp_line
			(start -0.67945 0.3048)
			(end -0.67945 -0.305054)
			(stroke
				(width 0.1)
				(type default)
			)
			(layer "F.Fab")
		)
		(pad "1" smd circle
			(at -0.40005 0 90)
			(size 0 0)
			(layers "F.Cu" "F.Mask" "F.Paste")
			(net "P3V3_AUX")
		)
		(pad "2" smd circle
			(at 0.40005 0 90)
			(size 0 0)
			(layers "F.Cu" "F.Mask" "F.Paste")
			(net "GND")
		)
	)
	(footprint ""
		(layer "F.Cu")
		(at 449.967858 -18.437098)
		(property "Reference" "R1736"
			(at 0 0 0)
			(layer "F.SilkS")
			(hide yes)
			(effects
				(font
					(size 1.27 1.27)
				)
			)
		)
		(property "Value" ""
			(at 0 0 0)
			(layer "F.Fab")
			(effects
				(font
					(size 1.27 1.27)
				)
			)
		)
		(duplicate_pad_numbers_are_jumpers no)
		(fp_line
			(start -0.7874 -0.4064)
			(end 0.7874 -0.4064)
			(stroke
				(width 0.1524)
				(type default)
			)
			(layer "F.SilkS")
		)
		(fp_line
			(start -0.7874 0.4064)
			(end -0.7874 -0.4064)
			(stroke
				(width 0.1524)
				(type default)
			)
			(layer "F.SilkS")
		)
		(fp_line
			(start 0.7874 -0.4064)
			(end 0.7874 0.4064)
			(stroke
				(width 0.1524)
				(type default)
			)
			(layer "F.SilkS")
		)
		(fp_line
			(start 0.7874 0.4064)
			(end -0.7874 0.4064)
			(stroke
				(width 0.1524)
				(type default)
			)
			(layer "F.SilkS")
		)
		(fp_line
			(start -0.67945 -0.305054)
			(end -0.12065 -0.305054)
			(stroke
				(width 0.1)
				(type default)
			)
			(layer "F.Fab")
		)
		(fp_line
			(start -0.67945 0.3048)
			(end -0.67945 -0.305054)
			(stroke
				(width 0.1)
				(type default)
			)
			(layer "F.Fab")
		)
		(fp_line
			(start -0.12065 -0.305054)
			(end -0.12065 -0.2794)
			(stroke
				(width 0.1)
				(type default)
			)
			(layer "F.Fab")
		)
		(fp_line
			(start -0.12065 -0.2794)
			(end 0.12065 -0.2794)
			(stroke
				(width 0.1)
				(type default)
			)
			(layer "F.Fab")
		)
		(fp_line
			(start -0.12065 0.2794)
			(end -0.12065 0.3048)
			(stroke
				(width 0.1)
				(type default)
			)
			(layer "F.Fab")
		)
		(fp_line
			(start -0.12065 0.3048)
			(end -0.67945 0.3048)
			(stroke
				(width 0.1)
				(type default)
			)
			(layer "F.Fab")
		)
		(fp_line
			(start 0.120396 0.2794)
			(end -0.12065 0.2794)
			(stroke
				(width 0.1)
				(type default)
			)
			(layer "F.Fab")
		)
		(fp_line
			(start 0.120396 0.3048)
			(end 0.120396 0.2794)
			(stroke
				(width 0.1)
				(type default)
			)
			(layer "F.Fab")
		)
		(fp_line
			(start 0.12065 -0.3048)
			(end 0.67945 -0.3048)
			(stroke
				(width 0.1)
				(type default)
			)
			(layer "F.Fab")
		)
		(fp_line
			(start 0.12065 -0.2794)
			(end 0.12065 -0.3048)
			(stroke
				(width 0.1)
				(type default)
			)
			(layer "F.Fab")
		)
		(fp_line
			(start 0.67945 -0.3048)
			(end 0.67945 0.3048)
			(stroke
				(width 0.1)
				(type default)
			)
			(layer "F.Fab")
		)
		(fp_line
			(start 0.67945 0.3048)
			(end 0.120396 0.3048)
			(stroke
				(width 0.1)
				(type default)
			)
			(layer "F.Fab")
		)
		(pad "1" smd circle
			(at -0.40005 0)
			(size 0 0)
			(layers "F.Cu" "F.Mask" "F.Paste")
			(net "SMB_ISO_SSD15_R_SCL")
		)
		(pad "2" smd circle
			(at 0.40005 0)
			(size 0 0)
			(layers "F.Cu" "F.Mask" "F.Paste")
			(net "SMB_ISO_SSD15_SCL")
		)
	)
)
